(kicad_pcb
	(version 20260206)
	(generator "pcbnew")
	(generator_version "10.0")
	(general
		(thickness 1.6)
		(legacy_teardrops no)
	)
	(paper "A4")
	(title_block
		(title "v1-chassis-manager — T6M_CM_d_v01_1031_1645.brd")
		(comment 1 "Open CloudServer (Microsoft) / footprints 466-474 of 2512")
	)
	(layers
		(0 "F.Cu" signal "TOP")
		(4 "In1.Cu" signal "GND1")
		(6 "In2.Cu" signal "IN1")
		(8 "In3.Cu" signal "VCC1")
		(10 "In4.Cu" signal "VCC2")
		(12 "In5.Cu" signal "GND2")
		(14 "In6.Cu" signal "IN2")
		(16 "In7.Cu" signal "IN3")
		(18 "In8.Cu" signal "GND3")
		(2 "B.Cu" signal "BOTTOM")
		(9 "F.Adhes" user "F.Adhesive")
		(11 "B.Adhes" user "B.Adhesive")
		(13 "F.Paste" user "Package Geometry/Pastemask Top")
		(15 "B.Paste" user "Package Geometry/Pastemask Bottom")
		(5 "F.SilkS" user "Ref Des/Silkscreen Top")
		(7 "B.SilkS" user "Ref Des/Silkscreen Bottom")
		(1 "F.Mask" user "Board Geometry/Soldermask Top")
		(3 "B.Mask" user "Board Geometry/Soldermask Bottom")
		(17 "Dwgs.User" user "User.Drawings")
		(19 "Cmts.User" user "User.Comments")
		(21 "Eco1.User" user "User.Eco1")
		(23 "Eco2.User" user "User.Eco2")
		(25 "Edge.Cuts" user "Board Geometry/Outline")
		(27 "Margin" user)
		(31 "F.CrtYd" user "Package Geometry/Place Bound Top")
		(29 "B.CrtYd" user "Package Geometry/Place Bound Bottom")
		(35 "F.Fab" user "Ref Des/Assembly Top")
		(33 "B.Fab" user "Ref Des/Assembly Bottom")
	)
	(footprint ""
		(layer "F.Cu")
		(at 112.81029 -156.330142 180)
		(property "Reference" "U107"
			(at -1.812036 3.072638 90)
			(unlocked yes)
			(layer "F.SilkS")
			(effects
				(font
					(size 0.635 0.4064)
					(thickness 0.1524)
				)
			)
		)
		(property "Value" ""
			(at 0 0 180)
			(layer "F.Fab")
			(effects
				(font
					(size 1.27 1.27)
				)
			)
		)
		(duplicate_pad_numbers_are_jumpers no)
		(fp_line
			(start 1.651 1.905)
			(end -1.651 1.905)
			(stroke
				(width 0.1524)
				(type default)
			)
			(layer "F.SilkS")
		)
		(fp_line
			(start 1.651 -1.905)
			(end 1.651 1.905)
			(stroke
				(width 0.1524)
				(type default)
			)
			(layer "F.SilkS")
		)
		(fp_line
			(start -1.651 1.905)
			(end -1.651 -1.905)
			(stroke
				(width 0.1524)
				(type default)
			)
			(layer "F.SilkS")
		)
		(fp_line
			(start -1.651 -1.905)
			(end 1.651 -1.905)
			(stroke
				(width 0.1524)
				(type default)
			)
			(layer "F.SilkS")
		)
		(fp_poly
			(pts
				(xy -1.524 0.7112) (xy -1.524 1.7526) (xy -0.508 1.7526) (xy -0.508 0.6985) (xy 0.508 0.6985) (xy 0.508 1.7526)
				(xy 1.524 1.7526) (xy 1.524 0.6985) (xy 1.524 -0.6985) (xy 0.508 -0.6985) (xy 0.508 -1.7526) (xy -0.508 -1.7526)
				(xy -0.508 -0.6985) (xy -1.524 -0.6985) (xy -1.524 0.6985)
			)
			(stroke
				(width 0)
				(type default)
			)
			(fill no)
			(layer "F.CrtYd")
		)
		(fp_text user "D"
			(at 1.13284 -0.98171 0)
			(unlocked yes)
			(layer "F.SilkS")
			(effects
				(font
					(size 0.635 0.4064)
					(thickness 0.1524)
				)
			)
		)
		(fp_text user "S"
			(at 0.12827 1.315466 0)
			(unlocked yes)
			(layer "F.SilkS")
			(effects
				(font
					(size 0.635 0.4064)
					(thickness 0.1524)
				)
			)
		)
		(fp_text user "G"
			(at -1.140968 -0.04064 0)
			(unlocked yes)
			(layer "F.SilkS")
			(effects
				(font
					(size 0.635 0.4064)
					(thickness 0.1524)
				)
			)
		)
		(pad "D" smd rect
			(at 0 -1.1176 180)
			(size 1.016 1.27)
			(layers "F.Cu" "F.Mask" "F.Paste")
			(net "N52410978")
		)
		(pad "G" smd rect
			(at -1.016 1.1176 180)
			(size 1.016 1.27)
			(layers "F.Cu" "F.Mask" "F.Paste")
			(net "POWER_SW2_PWR_CTR_N")
		)
		(pad "S" smd rect
			(at 1.016 1.1176 180)
			(size 1.016 1.27)
			(layers "F.Cu" "F.Mask" "F.Paste")
			(net "GND")
		)
	)
	(footprint ""
		(layer "F.Cu")
		(at 90.000074 -88.799924)
		(property "Reference" "H2"
			(at 2.474468 1.009904 0)
			(unlocked yes)
			(layer "F.SilkS")
			(effects
				(font
					(size 0.7874 0.5842)
					(thickness 0.1524)
				)
				(justify left)
			)
		)
		(property "Value" ""
			(at 0 0 0)
			(layer "F.Fab")
			(effects
				(font
					(size 1.27 1.27)
				)
			)
		)
		(duplicate_pad_numbers_are_jumpers no)
		(fp_circle
			(center 0 0)
			(end 2.3114 0)
			(stroke
				(width 0.1524)
				(type default)
			)
			(fill no)
			(layer "F.SilkS")
		)
		(fp_circle
			(center 0 0)
			(end 2.3114 0)
			(stroke
				(width 0.1524)
				(type default)
			)
			(fill no)
			(layer "B.SilkS")
		)
		(fp_poly
			(pts
				(arc
					(start 0 1.4986)
					(mid 0 -1.4986)
					(end 0 1.4986)
				)
			)
			(stroke
				(width 0)
				(type default)
			)
			(fill no)
			(layer "F.CrtYd")
		)
		(pad "" np_thru_hole circle
			(at 0 0)
			(size 2.9972 2.9972)
			(drill 2.9972)
			(layers "*.Cu" "*.Mask")
			(clearance 0.381)
			(thermal_gap 0.381)
		)
		(zone
			(layers "F.Cu" "B.Cu" "In1.Cu" "In2.Cu" "In3.Cu" "In4.Cu" "In5.Cu" "In6.Cu"
				"In7.Cu" "In8.Cu"
			)
			(hatch none 0.5)
			(connect_pads
				(clearance 0)
			)
			(min_thickness 0.25)
			(keepout
				(tracks not_allowed)
				(vias allowed)
				(pads allowed)
				(copperpour not_allowed)
				(footprints allowed)
			)
			(placement
				(enabled no)
				(sheetname "")
			)
			(fill
				(thermal_gap 0.5)
				(thermal_bridge_width 0.5)
				(island_removal_mode 0)
			)
			(polygon
				(pts
					(arc
						(start 90.000074 -86.793324)
						(mid 90.000074 -90.806524)
						(end 90.000074 -86.793324)
					)
				)
			)
		)
	)
	(footprint ""
		(layer "F.Cu")
		(at 109.817154 -140.337032 90)
		(property "Reference" "PR62"
			(at 2.675128 3.839972 90)
			(unlocked yes)
			(layer "F.SilkS")
			(effects
				(font
					(size 0.635 0.4064)
					(thickness 0.1524)
				)
				(justify left)
			)
		)
		(property "Value" ""
			(at 0 0 90)
			(layer "F.Fab")
			(effects
				(font
					(size 1.27 1.27)
				)
			)
		)
		(duplicate_pad_numbers_are_jumpers no)
		(fp_line
			(start 0.7874 -0.4064)
			(end 0.7874 0.4064)
			(stroke
				(width 0.1524)
				(type default)
			)
			(layer "F.SilkS")
		)
		(fp_line
			(start -0.7874 -0.4064)
			(end 0.7874 -0.4064)
			(stroke
				(width 0.1524)
				(type default)
			)
			(layer "F.SilkS")
		)
		(fp_line
			(start 0.7874 0.4064)
			(end -0.7874 0.4064)
			(stroke
				(width 0.1524)
				(type default)
			)
			(layer "F.SilkS")
		)
		(fp_line
			(start -0.7874 0.4064)
			(end -0.7874 -0.4064)
			(stroke
				(width 0.1524)
				(type default)
			)
			(layer "F.SilkS")
		)
		(fp_poly
			(pts
				(xy -0.508 0.2794) (xy -0.508 0.2286) (xy -0.635 0.2286) (xy -0.635 -0.254) (xy -0.5334 -0.254)
				(xy -0.5334 -0.2794) (xy 0.5334 -0.2794) (xy 0.5334 -0.254) (xy 0.635 -0.254) (xy 0.635 0.254) (xy 0.5334 0.254)
				(xy 0.5334 0.2794)
			)
			(stroke
				(width 0)
				(type default)
			)
			(fill no)
			(layer "F.CrtYd")
		)
		(pad "1" smd rect
			(at 0.40005 0 90)
			(size 0.4572 0.508)
			(layers "F.Cu" "F.Mask" "F.Paste")
			(net "AGND_PVCCP_NODE1")
		)
		(pad "2" smd rect
			(at -0.40005 0 90)
			(size 0.4572 0.508)
			(layers "F.Cu" "F.Mask" "F.Paste")
			(net "VR_PVCCP_NODE1_TEMPMAX")
		)
	)
	(footprint ""
		(layer "F.Cu")
		(at 79.963518 -85.93328 180)
		(property "Reference" "C23"
			(at 1.195578 -18.994374 0)
			(unlocked yes)
			(layer "F.SilkS")
			(effects
				(font
					(size 0.7874 0.5842)
					(thickness 0.1524)
				)
				(justify left)
			)
		)
		(property "Value" ""
			(at 0 0 180)
			(layer "F.Fab")
			(effects
				(font
					(size 1.27 1.27)
				)
			)
		)
		(duplicate_pad_numbers_are_jumpers no)
		(fp_line
			(start 0.7874 0.4064)
			(end -0.7874 0.4064)
			(stroke
				(width 0.1524)
				(type default)
			)
			(layer "F.SilkS")
		)
		(fp_line
			(start 0.7874 -0.4064)
			(end 0.7874 0.4064)
			(stroke
				(width 0.1524)
				(type default)
			)
			(layer "F.SilkS")
		)
		(fp_line
			(start 0 0.381)
			(end 0 -0.381)
			(stroke
				(width 0.1524)
				(type default)
			)
			(layer "F.SilkS")
		)
		(fp_line
			(start -0.7874 0.4064)
			(end -0.7874 -0.4064)
			(stroke
				(width 0.1524)
				(type default)
			)
			(layer "F.SilkS")
		)
		(fp_line
			(start -0.7874 -0.4064)
			(end 0.7874 -0.4064)
			(stroke
				(width 0.1524)
				(type default)
			)
			(layer "F.SilkS")
		)
		(fp_poly
			(pts
				(xy -0.5334 0.254) (xy -0.635 0.254) (xy -0.635 0.2286) (xy -0.635 -0.254) (xy -0.5334 -0.254) (xy -0.5334 -0.2794)
				(xy 0.5334 -0.2794) (xy 0.5334 -0.254) (xy 0.635 -0.254) (xy 0.635 0.254) (xy 0.5334 0.254) (xy 0.5334 0.2794)
				(xy -0.508 0.2794) (xy -0.5334 0.2794)
			)
			(stroke
				(width 0)
				(type default)
			)
			(fill no)
			(layer "F.CrtYd")
		)
		(pad "1" smd rect
			(at 0.40005 0 180)
			(size 0.4572 0.508)
			(layers "F.Cu" "F.Mask" "F.Paste")
			(net "A_CPU_NODE1_RTC_EXTPAD")
		)
		(pad "2" smd rect
			(at -0.40005 0 180)
			(size 0.4572 0.508)
			(layers "F.Cu" "F.Mask" "F.Paste")
			(net "GND")
		)
	)
	(footprint ""
		(layer "F.Cu")
		(at 82.699352 -145.237962)
		(property "Reference" "C836"
			(at -1.703832 -1.368806 0)
			(unlocked yes)
			(layer "F.SilkS")
			(effects
				(font
					(size 0.7874 0.5842)
					(thickness 0.1524)
				)
				(justify left)
			)
		)
		(property "Value" ""
			(at 0 0 0)
			(layer "F.Fab")
			(effects
				(font
					(size 1.27 1.27)
				)
			)
		)
		(duplicate_pad_numbers_are_jumpers no)
		(fp_line
			(start -1.905 -0.8636)
			(end 1.905 -0.8636)
			(stroke
				(width 0.1524)
				(type default)
			)
			(layer "F.SilkS")
		)
		(fp_line
			(start -1.905 0.8636)
			(end -1.905 -0.8636)
			(stroke
				(width 0.1524)
				(type default)
			)
			(layer "F.SilkS")
		)
		(fp_line
			(start 0 0.8382)
			(end 0 -0.8382)
			(stroke
				(width 0.1524)
				(type default)
			)
			(layer "F.SilkS")
		)
		(fp_line
			(start 1.905 -0.8636)
			(end 1.905 0.8636)
			(stroke
				(width 0.1524)
				(type default)
			)
			(layer "F.SilkS")
		)
		(fp_line
			(start 1.905 0.8636)
			(end -1.905 0.8636)
			(stroke
				(width 0.1524)
				(type default)
			)
			(layer "F.SilkS")
		)
		(fp_rect
			(start -1.524 0.7366)
			(end 1.524 -0.7366)
			(stroke
				(width 0)
				(type default)
			)
			(fill no)
			(layer "F.CrtYd")
		)
		(pad "1" smd rect
			(at 0.94996 0)
			(size 1.1176 1.3716)
			(layers "F.Cu" "F.Mask" "F.Paste")
			(net "P1V8_NODE1")
		)
		(pad "2" smd rect
			(at -0.94996 0)
			(size 1.1176 1.3716)
			(layers "F.Cu" "F.Mask" "F.Paste")
			(net "GND")
		)
	)
	(footprint ""
		(layer "F.Cu")
		(at 186.131708 -127.0254)
		(property "Reference" "R1290"
			(at 4.088892 19.78787 0)
			(unlocked yes)
			(layer "F.SilkS")
			(effects
				(font
					(size 0.7874 0.5842)
					(thickness 0.1524)
				)
				(justify left)
			)
		)
		(property "Value" ""
			(at 0 0 0)
			(layer "F.Fab")
			(effects
				(font
					(size 1.27 1.27)
				)
			)
		)
		(duplicate_pad_numbers_are_jumpers no)
		(fp_line
			(start -0.7874 -0.4064)
			(end 0.7874 -0.4064)
			(stroke
				(width 0.1524)
				(type default)
			)
			(layer "F.SilkS")
		)
		(fp_line
			(start -0.7874 0.4064)
			(end -0.7874 -0.4064)
			(stroke
				(width 0.1524)
				(type default)
			)
			(layer "F.SilkS")
		)
		(fp_line
			(start 0.7874 -0.4064)
			(end 0.7874 0.4064)
			(stroke
				(width 0.1524)
				(type default)
			)
			(layer "F.SilkS")
		)
		(fp_line
			(start 0.7874 0.4064)
			(end -0.7874 0.4064)
			(stroke
				(width 0.1524)
				(type default)
			)
			(layer "F.SilkS")
		)
		(fp_poly
			(pts
				(xy -0.508 0.2794) (xy -0.508 0.2286) (xy -0.635 0.2286) (xy -0.635 -0.254) (xy -0.5334 -0.254)
				(xy -0.5334 -0.2794) (xy 0.5334 -0.2794) (xy 0.5334 -0.254) (xy 0.635 -0.254) (xy 0.635 0.254) (xy 0.5334 0.254)
				(xy 0.5334 0.2794)
			)
			(stroke
				(width 0)
				(type default)
			)
			(fill no)
			(layer "F.CrtYd")
		)
		(pad "1" smd rect
			(at 0.40005 0)
			(size 0.4572 0.508)
			(layers "F.Cu" "F.Mask" "F.Paste")
			(net "SIO_JTAG_CPLD1_TDO")
		)
		(pad "2" smd rect
			(at -0.40005 0)
			(size 0.4572 0.508)
			(layers "F.Cu" "F.Mask" "F.Paste")
			(net "P3V3_NODE1")
		)
	)
	(footprint ""
		(layer "F.Cu")
		(at 139.43838 -74.301096 180)
		(property "Reference" "R508"
			(at -0.8763 2.141474 0)
			(unlocked yes)
			(layer "F.SilkS")
			(effects
				(font
					(size 0.7874 0.5842)
					(thickness 0.1524)
				)
				(justify left)
			)
		)
		(property "Value" ""
			(at 0 0 180)
			(layer "F.Fab")
			(effects
				(font
					(size 1.27 1.27)
				)
			)
		)
		(duplicate_pad_numbers_are_jumpers no)
		(fp_line
			(start 0.7874 0.4064)
			(end -0.7874 0.4064)
			(stroke
				(width 0.1524)
				(type default)
			)
			(layer "F.SilkS")
		)
		(fp_line
			(start 0.7874 -0.4064)
			(end 0.7874 0.4064)
			(stroke
				(width 0.1524)
				(type default)
			)
			(layer "F.SilkS")
		)
		(fp_line
			(start -0.7874 0.4064)
			(end -0.7874 -0.4064)
			(stroke
				(width 0.1524)
				(type default)
			)
			(layer "F.SilkS")
		)
		(fp_line
			(start -0.7874 -0.4064)
			(end 0.7874 -0.4064)
			(stroke
				(width 0.1524)
				(type default)
			)
			(layer "F.SilkS")
		)
		(fp_poly
			(pts
				(xy -0.508 0.2794) (xy -0.508 0.2286) (xy -0.635 0.2286) (xy -0.635 -0.254) (xy -0.5334 -0.254)
				(xy -0.5334 -0.2794) (xy 0.5334 -0.2794) (xy 0.5334 -0.254) (xy 0.635 -0.254) (xy 0.635 0.254) (xy 0.5334 0.254)
				(xy 0.5334 0.2794)
			)
			(stroke
				(width 0)
				(type default)
			)
			(fill no)
			(layer "F.CrtYd")
		)
		(pad "1" smd rect
			(at 0.40005 0 180)
			(size 0.4572 0.508)
			(layers "F.Cu" "F.Mask" "F.Paste")
			(net "SATA_SPI_CLK_NODE1")
		)
		(pad "2" smd rect
			(at -0.40005 0 180)
			(size 0.4572 0.508)
			(layers "F.Cu" "F.Mask" "F.Paste")
			(net "SATA_SPI_CLK_NODE1_R")
		)
	)
	(footprint ""
		(layer "F.Cu")
		(at 68.81876 -188.126624 90)
		(property "Reference" "C634"
			(at 4.548886 -0.734568 90)
			(unlocked yes)
			(layer "F.SilkS")
			(effects
				(font
					(size 0.7874 0.5842)
					(thickness 0.1524)
				)
				(justify left)
			)
		)
		(property "Value" ""
			(at 0 0 90)
			(layer "F.Fab")
			(effects
				(font
					(size 1.27 1.27)
				)
			)
		)
		(duplicate_pad_numbers_are_jumpers no)
		(fp_line
			(start 0.7874 -0.4064)
			(end 0.7874 0.4064)
			(stroke
				(width 0.1524)
				(type default)
			)
			(layer "F.SilkS")
		)
		(fp_line
			(start -0.7874 -0.4064)
			(end 0.7874 -0.4064)
			(stroke
				(width 0.1524)
				(type default)
			)
			(layer "F.SilkS")
		)
		(fp_line
			(start 0 0.381)
			(end 0 -0.381)
			(stroke
				(width 0.1524)
				(type default)
			)
			(layer "F.SilkS")
		)
		(fp_line
			(start 0.7874 0.4064)
			(end -0.7874 0.4064)
			(stroke
				(width 0.1524)
				(type default)
			)
			(layer "F.SilkS")
		)
		(fp_line
			(start -0.7874 0.4064)
			(end -0.7874 -0.4064)
			(stroke
				(width 0.1524)
				(type default)
			)
			(layer "F.SilkS")
		)
		(fp_poly
			(pts
				(xy -0.5334 0.254) (xy -0.635 0.254) (xy -0.635 0.2286) (xy -0.635 -0.254) (xy -0.5334 -0.254) (xy -0.5334 -0.2794)
				(xy 0.5334 -0.2794) (xy 0.5334 -0.254) (xy 0.635 -0.254) (xy 0.635 0.254) (xy 0.5334 0.254) (xy 0.5334 0.2794)
				(xy -0.508 0.2794) (xy -0.5334 0.2794)
			)
			(stroke
				(width 0)
				(type default)
			)
			(fill no)
			(layer "F.CrtYd")
		)
		(pad "1" smd rect
			(at 0.40005 0 90)
			(size 0.4572 0.508)
			(layers "F.Cu" "F.Mask" "F.Paste")
			(net "T2_NODE1_EN_R")
		)
		(pad "2" smd rect
			(at -0.40005 0 90)
			(size 0.4572 0.508)
			(layers "F.Cu" "F.Mask" "F.Paste")
			(net "GND")
		)
	)
	(footprint ""
		(layer "F.Cu")
		(at 76.179426 -99.086416)
		(property "Reference" "OSC5"
			(at -1.157986 -3.207258 0)
			(unlocked yes)
			(layer "F.SilkS")
			(effects
				(font
					(size 0.7874 0.5842)
					(thickness 0.1524)
				)
				(justify left)
			)
		)
		(property "Value" ""
			(at 0 0 0)
			(layer "F.Fab")
			(effects
				(font
					(size 1.27 1.27)
				)
			)
		)
		(duplicate_pad_numbers_are_jumpers no)
		(fp_line
			(start -0.6096 -0.7366)
			(end -0.6096 2.936494)
			(stroke
				(width 0.1524)
				(type default)
			)
			(layer "F.SilkS")
		)
		(fp_line
			(start -0.6096 2.936494)
			(end 2.35966 2.936494)
			(stroke
				(width 0.1524)
				(type default)
			)
			(layer "F.SilkS")
		)
		(fp_line
			(start 2.35966 -0.7366)
			(end -0.6096 -0.7366)
			(stroke
				(width 0.1524)
				(type default)
			)
			(layer "F.SilkS")
		)
		(fp_line
			(start 2.35966 2.936494)
			(end 2.35966 -0.7366)
			(stroke
				(width 0.1524)
				(type default)
			)
			(layer "F.SilkS")
		)
		(fp_poly
			(pts
				(xy -1.843278 0.508) (xy -1.843278 -0.508) (xy -0.827278 0)
			)
			(stroke
				(width 0)
				(type default)
			)
			(fill yes)
			(layer "F.SilkS")
		)
		(fp_poly
			(pts
				(xy -0.5334 -0.6604) (xy 0.5334 -0.6604) (xy 0.5334 -0.575056) (xy 1.21666 -0.575056) (xy 1.21666 -0.6604)
				(xy 2.28346 -0.6604) (xy 2.28346 0.6604) (xy 2.199894 0.6604) (xy 2.199894 1.539494) (xy 2.28346 1.539494)
				(xy 2.28346 2.860294) (xy 1.21666 2.860294) (xy 1.21666 2.77495) (xy 0.5334 2.77495) (xy 0.5334 2.860294)
				(xy -0.5334 2.860294) (xy -0.5334 1.539494) (xy -0.450088 1.539494) (xy -0.450088 0.6604) (xy -0.5334 0.6604)
			)
			(stroke
				(width 0)
				(type default)
			)
			(fill no)
			(layer "F.CrtYd")
		)
		(fp_line
			(start -0.450088 -0.575056)
			(end -0.450088 2.77495)
			(stroke
				(width 0.1)
				(type default)
			)
			(layer "F.Fab")
		)
		(fp_line
			(start -0.450088 2.77495)
			(end 2.199894 2.77495)
			(stroke
				(width 0.1)
				(type default)
			)
			(layer "F.Fab")
		)
		(fp_line
			(start 2.199894 -0.575056)
			(end -0.450088 -0.575056)
			(stroke
				(width 0.1)
				(type default)
			)
			(layer "F.Fab")
		)
		(fp_line
			(start 2.199894 2.77495)
			(end 2.199894 -0.575056)
			(stroke
				(width 0.1)
				(type default)
			)
			(layer "F.Fab")
		)
		(fp_poly
			(pts
				(xy -1.843278 0.508) (xy -1.843278 -0.508) (xy -0.827278 0)
			)
			(stroke
				(width 0)
				(type default)
			)
			(fill yes)
			(layer "F.Fab")
		)
		(pad "1" smd rect
			(at 0 0)
			(size 0.9652 1.2192)
			(layers "F.Cu" "F.Mask" "F.Paste")
			(net "FM_OSC_NODE1_OSC_NC")
		)
		(pad "2" smd rect
			(at 0 2.199894)
			(size 0.9652 1.2192)
			(layers "F.Cu" "F.Mask" "F.Paste")
			(net "GND")
		)
		(pad "3" smd rect
			(at 1.75006 2.199894)
			(size 0.9652 1.2192)
			(layers "F.Cu" "F.Mask" "F.Paste")
			(net "CLK_33K_CPU_NODE1_SUSCLK_R")
		)
		(pad "4" smd rect
			(at 1.75006 0)
			(size 0.9652 1.2192)
			(layers "F.Cu" "F.Mask" "F.Paste")
			(net "P3V3_STB_NODE1")
		)
	)
)
